(kicad_pcb
	(version 20260206)
	(generator "pcbnew")
	(generator_version "10.0")
	(general
		(thickness 1.6)
		(legacy_teardrops no)
	)
	(paper "A4")
	(title_block
		(title "01162023_DA0F0TEBIF0_F0T_Expander_BD_F_brd_V02_OCP.brd")
		(comment 1 "Grand Teton / footprints 1389-1395 of 9728")
	)
	(layers
		(0 "F.Cu" signal "TOP")
		(4 "In1.Cu" signal "GND")
		(6 "In2.Cu" signal "VCC")
		(8 "In3.Cu" signal "VCC1")
		(10 "In4.Cu" signal "GND1")
		(12 "In5.Cu" signal "IN1")
		(14 "In6.Cu" signal "GND2")
		(16 "In7.Cu" signal "IN2")
		(18 "In8.Cu" signal "GND3")
		(20 "In9.Cu" signal "IN3")
		(22 "In10.Cu" signal "GND4")
		(24 "In11.Cu" signal "IN4")
		(26 "In12.Cu" signal "GND5")
		(28 "In13.Cu" signal "IN5")
		(30 "In14.Cu" signal "GND6")
		(32 "In15.Cu" signal "IN6")
		(34 "In16.Cu" signal "GND7")
		(2 "B.Cu" signal "BOTTOM")
		(9 "F.Adhes" user "F.Adhesive")
		(11 "B.Adhes" user "B.Adhesive")
		(13 "F.Paste" user "Package Geometry/Pastemask Top")
		(15 "B.Paste" user "Package Geometry/Pastemask Bottom")
		(5 "F.SilkS" user "Ref Des/Silkscreen Top")
		(7 "B.SilkS" user "Ref Des/Silkscreen Bottom")
		(1 "F.Mask" user "Board Geometry/Soldermask Top")
		(3 "B.Mask" user "Board Geometry/Soldermask Bottom")
		(17 "Dwgs.User" user "User.Drawings")
		(19 "Cmts.User" user "User.Comments")
		(21 "Eco1.User" user "User.Eco1")
		(23 "Eco2.User" user "User.Eco2")
		(25 "Edge.Cuts" user "Board Geometry/Outline")
		(27 "Margin" user)
		(31 "F.CrtYd" user "Package Geometry/Place Bound Top")
		(29 "B.CrtYd" user "Package Geometry/Place Bound Bottom")
		(35 "F.Fab" user "Ref Des/Assembly Top")
		(33 "B.Fab" user "Ref Des/Assembly Bottom")
	)
	(footprint ""
		(layer "F.Cu")
		(at 259.130038 -284.404308 -90)
		(property "Reference" "C3385"
			(at 0 0 270)
			(layer "F.SilkS")
			(hide yes)
			(effects
				(font
					(size 1.27 1.27)
				)
			)
		)
		(property "Value" ""
			(at 0 0 270)
			(layer "F.Fab")
			(effects
				(font
					(size 1.27 1.27)
				)
			)
		)
		(duplicate_pad_numbers_are_jumpers no)
		(fp_line
			(start -1.2954 0.5842)
			(end -1.2954 -0.5842)
			(stroke
				(width 0.1524)
				(type default)
			)
			(layer "F.SilkS")
		)
		(fp_line
			(start 1.2954 0.5842)
			(end -1.2954 0.5842)
			(stroke
				(width 0.1524)
				(type default)
			)
			(layer "F.SilkS")
		)
		(fp_line
			(start -1.2954 -0.5842)
			(end 1.2954 -0.5842)
			(stroke
				(width 0.1524)
				(type default)
			)
			(layer "F.SilkS")
		)
		(fp_line
			(start 1.2954 -0.5842)
			(end 1.2954 0.5842)
			(stroke
				(width 0.1524)
				(type default)
			)
			(layer "F.SilkS")
		)
		(fp_line
			(start -0.8636 0.4572)
			(end -0.8636 0.4064)
			(stroke
				(width 0.1)
				(type default)
			)
			(layer "F.Fab")
		)
		(fp_line
			(start 0.8636 0.4572)
			(end -0.8636 0.4572)
			(stroke
				(width 0.1)
				(type default)
			)
			(layer "F.Fab")
		)
		(fp_line
			(start -1.1938 0.4064)
			(end -1.1938 -0.4064)
			(stroke
				(width 0.1)
				(type default)
			)
			(layer "F.Fab")
		)
		(fp_line
			(start -0.8636 0.4064)
			(end -1.1938 0.4064)
			(stroke
				(width 0.1)
				(type default)
			)
			(layer "F.Fab")
		)
		(fp_line
			(start 0.8636 0.4064)
			(end 0.8636 0.4572)
			(stroke
				(width 0.1)
				(type default)
			)
			(layer "F.Fab")
		)
		(fp_line
			(start 1.1938 0.4064)
			(end 0.8636 0.4064)
			(stroke
				(width 0.1)
				(type default)
			)
			(layer "F.Fab")
		)
		(fp_line
			(start -1.1938 -0.4064)
			(end -0.8636 -0.4064)
			(stroke
				(width 0.1)
				(type default)
			)
			(layer "F.Fab")
		)
		(fp_line
			(start -0.8636 -0.4064)
			(end -0.8636 -0.4572)
			(stroke
				(width 0.1)
				(type default)
			)
			(layer "F.Fab")
		)
		(fp_line
			(start 0.8636 -0.4064)
			(end 1.1938 -0.4064)
			(stroke
				(width 0.1)
				(type default)
			)
			(layer "F.Fab")
		)
		(fp_line
			(start 1.1938 -0.4064)
			(end 1.1938 0.4064)
			(stroke
				(width 0.1)
				(type default)
			)
			(layer "F.Fab")
		)
		(fp_line
			(start -0.8636 -0.4572)
			(end 0.8636 -0.4572)
			(stroke
				(width 0.1)
				(type default)
			)
			(layer "F.Fab")
		)
		(fp_line
			(start 0.8636 -0.4572)
			(end 0.8636 -0.4064)
			(stroke
				(width 0.1)
				(type default)
			)
			(layer "F.Fab")
		)
		(pad "1" smd rect
			(at -0.7366 0 180)
			(size 0.7112 0.8128)
			(layers "F.Cu" "F.Mask" "F.Paste")
			(net "P1V8_PLL0_PEX2")
		)
		(pad "2" smd rect
			(at 0.7366 0 180)
			(size 0.7112 0.8128)
			(layers "F.Cu" "F.Mask" "F.Paste")
			(net "GND")
		)
	)
	(footprint ""
		(layer "F.Cu")
		(at 39.280592 -103.803196)
		(property "Reference" "C60"
			(at 0 0 0)
			(layer "F.SilkS")
			(hide yes)
			(effects
				(font
					(size 1.27 1.27)
				)
			)
		)
		(property "Value" ""
			(at 0 0 0)
			(layer "F.Fab")
			(effects
				(font
					(size 1.27 1.27)
				)
			)
		)
		(duplicate_pad_numbers_are_jumpers no)
		(fp_line
			(start -0.299974 -0.150114)
			(end 0.299974 -0.150114)
			(stroke
				(width 0.1)
				(type default)
			)
			(layer "F.Fab")
		)
		(fp_line
			(start -0.299974 0.150114)
			(end -0.299974 -0.150114)
			(stroke
				(width 0.1)
				(type default)
			)
			(layer "F.Fab")
		)
		(fp_line
			(start 0.299974 -0.150114)
			(end 0.299974 0.150114)
			(stroke
				(width 0.1)
				(type default)
			)
			(layer "F.Fab")
		)
		(fp_line
			(start 0.299974 0.150114)
			(end -0.299974 0.150114)
			(stroke
				(width 0.1)
				(type default)
			)
			(layer "F.Fab")
		)
		(pad "1" smd rect
			(at -0.2667 0)
			(size 0.3048 0.381)
			(layers "F.Cu" "F.Mask" "F.Paste")
			(net "P5E_PEX0_STN1_TX_DN<18>")
		)
		(pad "2" smd rect
			(at 0.2667 0)
			(size 0.3048 0.381)
			(layers "F.Cu" "F.Mask" "F.Paste")
			(net "P5E_PEX0_STN1_TX_C_DN<18>")
		)
	)
	(footprint ""
		(layer "F.Cu")
		(at 199.047354 -36.686998 90)
		(property "Reference" "C3666"
			(at 0 0 90)
			(layer "F.SilkS")
			(hide yes)
			(effects
				(font
					(size 1.27 1.27)
				)
			)
		)
		(property "Value" ""
			(at 0 0 90)
			(layer "F.Fab")
			(effects
				(font
					(size 1.27 1.27)
				)
			)
		)
		(duplicate_pad_numbers_are_jumpers no)
		(fp_line
			(start 0.7874 -0.4064)
			(end 0.7874 0.4064)
			(stroke
				(width 0.1524)
				(type default)
			)
			(layer "F.SilkS")
		)
		(fp_line
			(start -0.7874 -0.4064)
			(end 0.7874 -0.4064)
			(stroke
				(width 0.1524)
				(type default)
			)
			(layer "F.SilkS")
		)
		(fp_line
			(start 0.7874 0.4064)
			(end -0.7874 0.4064)
			(stroke
				(width 0.1524)
				(type default)
			)
			(layer "F.SilkS")
		)
		(fp_line
			(start -0.7874 0.4064)
			(end -0.7874 -0.4064)
			(stroke
				(width 0.1524)
				(type default)
			)
			(layer "F.SilkS")
		)
		(fp_line
			(start -0.12065 -0.305054)
			(end -0.12065 -0.2794)
			(stroke
				(width 0.1)
				(type default)
			)
			(layer "F.Fab")
		)
		(fp_line
			(start -0.67945 -0.305054)
			(end -0.12065 -0.305054)
			(stroke
				(width 0.1)
				(type default)
			)
			(layer "F.Fab")
		)
		(fp_line
			(start 0.67945 -0.3048)
			(end 0.67945 0.3048)
			(stroke
				(width 0.1)
				(type default)
			)
			(layer "F.Fab")
		)
		(fp_line
			(start 0.12065 -0.3048)
			(end 0.67945 -0.3048)
			(stroke
				(width 0.1)
				(type default)
			)
			(layer "F.Fab")
		)
		(fp_line
			(start 0.12065 -0.2794)
			(end 0.12065 -0.3048)
			(stroke
				(width 0.1)
				(type default)
			)
			(layer "F.Fab")
		)
		(fp_line
			(start -0.12065 -0.2794)
			(end 0.12065 -0.2794)
			(stroke
				(width 0.1)
				(type default)
			)
			(layer "F.Fab")
		)
		(fp_line
			(start 0.120396 0.2794)
			(end -0.12065 0.2794)
			(stroke
				(width 0.1)
				(type default)
			)
			(layer "F.Fab")
		)
		(fp_line
			(start -0.12065 0.2794)
			(end -0.12065 0.3048)
			(stroke
				(width 0.1)
				(type default)
			)
			(layer "F.Fab")
		)
		(fp_line
			(start 0.67945 0.3048)
			(end 0.120396 0.3048)
			(stroke
				(width 0.1)
				(type default)
			)
			(layer "F.Fab")
		)
		(fp_line
			(start 0.120396 0.3048)
			(end 0.120396 0.2794)
			(stroke
				(width 0.1)
				(type default)
			)
			(layer "F.Fab")
		)
		(fp_line
			(start -0.12065 0.3048)
			(end -0.67945 0.3048)
			(stroke
				(width 0.1)
				(type default)
			)
			(layer "F.Fab")
		)
		(fp_line
			(start -0.67945 0.3048)
			(end -0.67945 -0.305054)
			(stroke
				(width 0.1)
				(type default)
			)
			(layer "F.Fab")
		)
		(pad "1" smd circle
			(at -0.40005 0 90)
			(size 0 0)
			(layers "F.Cu" "F.Mask" "F.Paste")
			(net "P3V3_AUX")
		)
		(pad "2" smd circle
			(at 0.40005 0 90)
			(size 0 0)
			(layers "F.Cu" "F.Mask" "F.Paste")
			(net "GND")
		)
	)
	(footprint ""
		(layer "F.Cu")
		(at 229.48265 -310.571642 180)
		(property "Reference" "PR171"
			(at 0 0 180)
			(layer "F.SilkS")
			(hide yes)
			(effects
				(font
					(size 1.27 1.27)
				)
			)
		)
		(property "Value" ""
			(at 0 0 180)
			(layer "F.Fab")
			(effects
				(font
					(size 1.27 1.27)
				)
			)
		)
		(duplicate_pad_numbers_are_jumpers no)
		(fp_line
			(start 0.7874 0.4064)
			(end -0.7874 0.4064)
			(stroke
				(width 0.1524)
				(type default)
			)
			(layer "F.SilkS")
		)
		(fp_line
			(start 0.7874 -0.4064)
			(end 0.7874 0.4064)
			(stroke
				(width 0.1524)
				(type default)
			)
			(layer "F.SilkS")
		)
		(fp_line
			(start -0.7874 0.4064)
			(end -0.7874 -0.4064)
			(stroke
				(width 0.1524)
				(type default)
			)
			(layer "F.SilkS")
		)
		(fp_line
			(start -0.7874 -0.4064)
			(end 0.7874 -0.4064)
			(stroke
				(width 0.1524)
				(type default)
			)
			(layer "F.SilkS")
		)
		(fp_line
			(start 0.67945 0.3048)
			(end 0.120396 0.3048)
			(stroke
				(width 0.1)
				(type default)
			)
			(layer "F.Fab")
		)
		(fp_line
			(start 0.67945 -0.3048)
			(end 0.67945 0.3048)
			(stroke
				(width 0.1)
				(type default)
			)
			(layer "F.Fab")
		)
		(fp_line
			(start 0.12065 -0.2794)
			(end 0.12065 -0.3048)
			(stroke
				(width 0.1)
				(type default)
			)
			(layer "F.Fab")
		)
		(fp_line
			(start 0.12065 -0.3048)
			(end 0.67945 -0.3048)
			(stroke
				(width 0.1)
				(type default)
			)
			(layer "F.Fab")
		)
		(fp_line
			(start 0.120396 0.3048)
			(end 0.120396 0.2794)
			(stroke
				(width 0.1)
				(type default)
			)
			(layer "F.Fab")
		)
		(fp_line
			(start 0.120396 0.2794)
			(end -0.12065 0.2794)
			(stroke
				(width 0.1)
				(type default)
			)
			(layer "F.Fab")
		)
		(fp_line
			(start -0.12065 0.3048)
			(end -0.67945 0.3048)
			(stroke
				(width 0.1)
				(type default)
			)
			(layer "F.Fab")
		)
		(fp_line
			(start -0.12065 0.2794)
			(end -0.12065 0.3048)
			(stroke
				(width 0.1)
				(type default)
			)
			(layer "F.Fab")
		)
		(fp_line
			(start -0.12065 -0.2794)
			(end 0.12065 -0.2794)
			(stroke
				(width 0.1)
				(type default)
			)
			(layer "F.Fab")
		)
		(fp_line
			(start -0.12065 -0.305054)
			(end -0.12065 -0.2794)
			(stroke
				(width 0.1)
				(type default)
			)
			(layer "F.Fab")
		)
		(fp_line
			(start -0.67945 0.3048)
			(end -0.67945 -0.305054)
			(stroke
				(width 0.1)
				(type default)
			)
			(layer "F.Fab")
		)
		(fp_line
			(start -0.67945 -0.305054)
			(end -0.12065 -0.305054)
			(stroke
				(width 0.1)
				(type default)
			)
			(layer "F.Fab")
		)
		(pad "1" smd circle
			(at -0.40005 0 180)
			(size 0 0)
			(layers "F.Cu" "F.Mask" "F.Paste")
			(net "SH_P1V25_PEX1_FB_P")
		)
		(pad "2" smd circle
			(at 0.40005 0 180)
			(size 0 0)
			(layers "F.Cu" "F.Mask" "F.Paste")
			(net "P1V25_PEX1_FB")
		)
	)
	(footprint ""
		(layer "F.Cu")
		(at 130.26263 -111.377476 -90)
		(property "Reference" "PR7013"
			(at 0 0 270)
			(layer "F.SilkS")
			(hide yes)
			(effects
				(font
					(size 1.27 1.27)
				)
			)
		)
		(property "Value" ""
			(at 0 0 270)
			(layer "F.Fab")
			(effects
				(font
					(size 1.27 1.27)
				)
			)
		)
		(duplicate_pad_numbers_are_jumpers no)
		(fp_line
			(start -0.7874 0.4064)
			(end -0.7874 -0.4064)
			(stroke
				(width 0.1524)
				(type default)
			)
			(layer "F.SilkS")
		)
		(fp_line
			(start 0.7874 0.4064)
			(end -0.7874 0.4064)
			(stroke
				(width 0.1524)
				(type default)
			)
			(layer "F.SilkS")
		)
		(fp_line
			(start -0.7874 -0.4064)
			(end 0.7874 -0.4064)
			(stroke
				(width 0.1524)
				(type default)
			)
			(layer "F.SilkS")
		)
		(fp_line
			(start 0.7874 -0.4064)
			(end 0.7874 0.4064)
			(stroke
				(width 0.1524)
				(type default)
			)
			(layer "F.SilkS")
		)
		(fp_line
			(start -0.67945 0.3048)
			(end -0.67945 -0.305054)
			(stroke
				(width 0.1)
				(type default)
			)
			(layer "F.Fab")
		)
		(fp_line
			(start -0.12065 0.3048)
			(end -0.67945 0.3048)
			(stroke
				(width 0.1)
				(type default)
			)
			(layer "F.Fab")
		)
		(fp_line
			(start 0.120396 0.3048)
			(end 0.120396 0.2794)
			(stroke
				(width 0.1)
				(type default)
			)
			(layer "F.Fab")
		)
		(fp_line
			(start 0.67945 0.3048)
			(end 0.120396 0.3048)
			(stroke
				(width 0.1)
				(type default)
			)
			(layer "F.Fab")
		)
		(fp_line
			(start -0.12065 0.2794)
			(end -0.12065 0.3048)
			(stroke
				(width 0.1)
				(type default)
			)
			(layer "F.Fab")
		)
		(fp_line
			(start 0.120396 0.2794)
			(end -0.12065 0.2794)
			(stroke
				(width 0.1)
				(type default)
			)
			(layer "F.Fab")
		)
		(fp_line
			(start -0.12065 -0.2794)
			(end 0.12065 -0.2794)
			(stroke
				(width 0.1)
				(type default)
			)
			(layer "F.Fab")
		)
		(fp_line
			(start 0.12065 -0.2794)
			(end 0.12065 -0.3048)
			(stroke
				(width 0.1)
				(type default)
			)
			(layer "F.Fab")
		)
		(fp_line
			(start 0.12065 -0.3048)
			(end 0.67945 -0.3048)
			(stroke
				(width 0.1)
				(type default)
			)
			(layer "F.Fab")
		)
		(fp_line
			(start 0.67945 -0.3048)
			(end 0.67945 0.3048)
			(stroke
				(width 0.1)
				(type default)
			)
			(layer "F.Fab")
		)
		(fp_line
			(start -0.67945 -0.305054)
			(end -0.12065 -0.305054)
			(stroke
				(width 0.1)
				(type default)
			)
			(layer "F.Fab")
		)
		(fp_line
			(start -0.12065 -0.305054)
			(end -0.12065 -0.2794)
			(stroke
				(width 0.1)
				(type default)
			)
			(layer "F.Fab")
		)
		(pad "1" smd circle
			(at -0.40005 0 270)
			(size 0 0)
			(layers "F.Cu" "F.Mask" "F.Paste")
			(net "P3V3_NIC2_CO_ILIMIT")
		)
		(pad "2" smd circle
			(at 0.40005 0 270)
			(size 0 0)
			(layers "F.Cu" "F.Mask" "F.Paste")
			(net "GND")
		)
	)
	(footprint ""
		(layer "F.Cu")
		(at 369.08359 -7.719822)
		(property "Reference" "R5818"
			(at 0 0 0)
			(layer "F.SilkS")
			(hide yes)
			(effects
				(font
					(size 1.27 1.27)
				)
			)
		)
		(property "Value" ""
			(at 0 0 0)
			(layer "F.Fab")
			(effects
				(font
					(size 1.27 1.27)
				)
			)
		)
		(duplicate_pad_numbers_are_jumpers no)
		(fp_line
			(start -0.7874 -0.4064)
			(end 0.7874 -0.4064)
			(stroke
				(width 0.1524)
				(type default)
			)
			(layer "F.SilkS")
		)
		(fp_line
			(start -0.7874 0.4064)
			(end -0.7874 -0.4064)
			(stroke
				(width 0.1524)
				(type default)
			)
			(layer "F.SilkS")
		)
		(fp_line
			(start 0.7874 -0.4064)
			(end 0.7874 0.4064)
			(stroke
				(width 0.1524)
				(type default)
			)
			(layer "F.SilkS")
		)
		(fp_line
			(start 0.7874 0.4064)
			(end -0.7874 0.4064)
			(stroke
				(width 0.1524)
				(type default)
			)
			(layer "F.SilkS")
		)
		(fp_line
			(start -0.67945 -0.305054)
			(end -0.12065 -0.305054)
			(stroke
				(width 0.1)
				(type default)
			)
			(layer "F.Fab")
		)
		(fp_line
			(start -0.67945 0.3048)
			(end -0.67945 -0.305054)
			(stroke
				(width 0.1)
				(type default)
			)
			(layer "F.Fab")
		)
		(fp_line
			(start -0.12065 -0.305054)
			(end -0.12065 -0.2794)
			(stroke
				(width 0.1)
				(type default)
			)
			(layer "F.Fab")
		)
		(fp_line
			(start -0.12065 -0.2794)
			(end 0.12065 -0.2794)
			(stroke
				(width 0.1)
				(type default)
			)
			(layer "F.Fab")
		)
		(fp_line
			(start -0.12065 0.2794)
			(end -0.12065 0.3048)
			(stroke
				(width 0.1)
				(type default)
			)
			(layer "F.Fab")
		)
		(fp_line
			(start -0.12065 0.3048)
			(end -0.67945 0.3048)
			(stroke
				(width 0.1)
				(type default)
			)
			(layer "F.Fab")
		)
		(fp_line
			(start 0.120396 0.2794)
			(end -0.12065 0.2794)
			(stroke
				(width 0.1)
				(type default)
			)
			(layer "F.Fab")
		)
		(fp_line
			(start 0.120396 0.3048)
			(end 0.120396 0.2794)
			(stroke
				(width 0.1)
				(type default)
			)
			(layer "F.Fab")
		)
		(fp_line
			(start 0.12065 -0.3048)
			(end 0.67945 -0.3048)
			(stroke
				(width 0.1)
				(type default)
			)
			(layer "F.Fab")
		)
		(fp_line
			(start 0.12065 -0.2794)
			(end 0.12065 -0.3048)
			(stroke
				(width 0.1)
				(type default)
			)
			(layer "F.Fab")
		)
		(fp_line
			(start 0.67945 -0.3048)
			(end 0.67945 0.3048)
			(stroke
				(width 0.1)
				(type default)
			)
			(layer "F.Fab")
		)
		(fp_line
			(start 0.67945 0.3048)
			(end 0.120396 0.3048)
			(stroke
				(width 0.1)
				(type default)
			)
			(layer "F.Fab")
		)
		(pad "1" smd circle
			(at -0.40005 0)
			(size 0 0)
			(layers "F.Cu" "F.Mask" "F.Paste")
			(net "SMB_BIC_I2C6_MUX_THERMAL_R_SDA")
		)
		(pad "2" smd circle
			(at 0.40005 0)
			(size 0 0)
			(layers "F.Cu" "F.Mask" "F.Paste")
			(net "SMB_LM75_3_SDA")
		)
	)
	(footprint ""
		(layer "F.Cu")
		(at 399.348452 -166.302944 90)
		(property "Reference" "R351"
			(at 0 0 90)
			(layer "F.SilkS")
			(hide yes)
			(effects
				(font
					(size 1.27 1.27)
				)
			)
		)
		(property "Value" ""
			(at 0 0 90)
			(layer "F.Fab")
			(effects
				(font
					(size 1.27 1.27)
				)
			)
		)
		(duplicate_pad_numbers_are_jumpers no)
		(fp_line
			(start 0.7874 -0.4064)
			(end 0.7874 0.4064)
			(stroke
				(width 0.1524)
				(type default)
			)
			(layer "F.SilkS")
		)
		(fp_line
			(start -0.7874 -0.4064)
			(end 0.7874 -0.4064)
			(stroke
				(width 0.1524)
				(type default)
			)
			(layer "F.SilkS")
		)
		(fp_line
			(start 0.7874 0.4064)
			(end -0.7874 0.4064)
			(stroke
				(width 0.1524)
				(type default)
			)
			(layer "F.SilkS")
		)
		(fp_line
			(start -0.7874 0.4064)
			(end -0.7874 -0.4064)
			(stroke
				(width 0.1524)
				(type default)
			)
			(layer "F.SilkS")
		)
		(fp_line
			(start -0.12065 -0.305054)
			(end -0.12065 -0.2794)
			(stroke
				(width 0.1)
				(type default)
			)
			(layer "F.Fab")
		)
		(fp_line
			(start -0.67945 -0.305054)
			(end -0.12065 -0.305054)
			(stroke
				(width 0.1)
				(type default)
			)
			(layer "F.Fab")
		)
		(fp_line
			(start 0.67945 -0.3048)
			(end 0.67945 0.3048)
			(stroke
				(width 0.1)
				(type default)
			)
			(layer "F.Fab")
		)
		(fp_line
			(start 0.12065 -0.3048)
			(end 0.67945 -0.3048)
			(stroke
				(width 0.1)
				(type default)
			)
			(layer "F.Fab")
		)
		(fp_line
			(start 0.12065 -0.2794)
			(end 0.12065 -0.3048)
			(stroke
				(width 0.1)
				(type default)
			)
			(layer "F.Fab")
		)
		(fp_line
			(start -0.12065 -0.2794)
			(end 0.12065 -0.2794)
			(stroke
				(width 0.1)
				(type default)
			)
			(layer "F.Fab")
		)
		(fp_line
			(start 0.120396 0.2794)
			(end -0.12065 0.2794)
			(stroke
				(width 0.1)
				(type default)
			)
			(layer "F.Fab")
		)
		(fp_line
			(start -0.12065 0.2794)
			(end -0.12065 0.3048)
			(stroke
				(width 0.1)
				(type default)
			)
			(layer "F.Fab")
		)
		(fp_line
			(start 0.67945 0.3048)
			(end 0.120396 0.3048)
			(stroke
				(width 0.1)
				(type default)
			)
			(layer "F.Fab")
		)
		(fp_line
			(start 0.120396 0.3048)
			(end 0.120396 0.2794)
			(stroke
				(width 0.1)
				(type default)
			)
			(layer "F.Fab")
		)
		(fp_line
			(start -0.12065 0.3048)
			(end -0.67945 0.3048)
			(stroke
				(width 0.1)
				(type default)
			)
			(layer "F.Fab")
		)
		(fp_line
			(start -0.67945 0.3048)
			(end -0.67945 -0.305054)
			(stroke
				(width 0.1)
				(type default)
			)
			(layer "F.Fab")
		)
		(pad "1" smd circle
			(at -0.40005 0 90)
			(size 0 0)
			(layers "F.Cu" "F.Mask" "F.Paste")
			(net "RST_NIC6_PERST0_R_N")
		)
		(pad "2" smd circle
			(at 0.40005 0 90)
			(size 0 0)
			(layers "F.Cu" "F.Mask" "F.Paste")
			(net "RST_HP_NIC6_BUF_N")
		)
	)
)
